FILE_TYPE = MACRO_DRAWING;
SET COLOR_WIRE YELLOW;
SET COLOR_PROP ORANGE;
SET COLOR_DOT WHITE;
SET COLOR_ARC YELLOW;
SET COLOR_BODY GREEN;
SET COLOR_NOTE PURPLE;
SET PROP_DISPLAY VALUE;
SET PAGE_NUMBER P114;
FORCEADD QUANTA_TITLE_BLOCK_C..1
(0 0);
FORCEPROP 1 LAST CUSTOM_TXT_CDS <NAME_2>
J 0
(-3175 50);
FORCEPROP 1 LAST CUSTOM_TXT_CDS <NAME_1>
J 0
(-3175 175);
FORCEPROP 1 LAST CUSTOM_TXT_CDS <Q_NUMBER>
J 0
(-1403 103);
DISPLAY 1.212766 (-1403 103);
FORCEPROP 1 LAST CUSTOM_TXT_CDS <Q_PROJ>
J 0
(-2382 102);
DISPLAY 1.212766 (-2382 102);
FORCEPROP 1 LAST CUSTOM_TXT_CDS <Q_REV>
J 0
(-184 103);
DISPLAY 1.212766 (-184 103);
FORCEPROP 1 LAST CUSTOM_TXT_CDS <CON_LAST_MODIFIED>
J 0
(-1885 15);
DISPLAY 0.978723 (-1885 15);
FORCEPROP 1 LAST CUSTOM_TXT_CDS <CON_PAGE_NUM> OF <CON_TOTAL_PAGES>
J 0
(-446 18);
DISPLAY 0.978723 (-446 18);
FORCEPROP 1 LAST Q_TITLE PCIE X32 SLOT1
J 0
(-9225 75);
DISPLAY 2.446809 (-9225 75);
PAINT GREEN (-9225 75);
FORCEPROP 1 LAST Q_DEPT BU9
J 1
(-3763 49);
DISPLAY 1.957447 (-3763 49);
PAINT GREEN (-3763 49);
FORCEPROP 2 LAST CDS_XR_PAGE_TITLE CR-114 : @T6G_MB_LIB.T6G(SCH_1):PAGE114
J 0
(-7890 5250);
DISPLAY 0.638298 (-7890 5250);
PAINT PINK (-7890 5250);
DISPLAY INVISIBLE (-7890 5250);
FORCEPROP 1 LAST COMMENT_BODY TRUE
J 0
(12 -13);
DISPLAY 0.978723 (12 -13);
PAINT GREEN (12 -13);
DISPLAY INVISIBLE (12 -13);
FORCEPROP 1 LAST CDS_LMAN_SYM_OUTLINE -9475,6775,100,-125
J 0
(0 0);
DISPLAY 0.468085 (0 0);
PAINT GREEN (0 0);
DISPLAY INVISIBLE (0 0);
FORCEPROP 2 LAST CDS_LIB pure_quanta
J 0
(0 0);
DISPLAY INVISIBLE (0 0);
FORCEPROP 2 LAST PAGE_BORDER TRUE
J 0
(-7890 5250);
DISPLAY 0.638298 (-7890 5250);
PAINT PINK (-7890 5250);
DISPLAY INVISIBLE (-7890 5250);
FORCEPROP 2 LAST CUSTOM_TXT_CDS <XR_PAGE_TITLE>
J 0
(-7890 5250);
DISPLAY 0.638298 (-7890 5250);
PAINT PINK (-7890 5250);
DISPLAY INVISIBLE (-7890 5250);
FORCEPROP 0 LAST CDS_CON_LAST_MODIFIED Wed Mar 09 16:31:20 2022
J 0
(-1885 15);
DISPLAY INVISIBLE (-1885 15);
QUIT
